(kicad_pcb
	(version 20260206)
	(generator "pcbnew")
	(generator_version "10.0")
	(general
		(thickness 1.6)
		(legacy_teardrops no)
	)
	(paper "A4")
	(title_block
		(title "Bryce Canyon_R.DPB_16317-1_OCP.brd")
		(comment 1 "Bryce Canyon / footprints 1402-1407 of 2099")
	)
	(layers
		(0 "F.Cu" signal "TOP")
		(4 "In1.Cu" signal "L2GND")
		(6 "In2.Cu" signal "L3")
		(8 "In3.Cu" signal "L4VCC")
		(10 "In4.Cu" signal "L5VCC")
		(12 "In5.Cu" signal "L6")
		(14 "In6.Cu" signal "L7GND")
		(2 "B.Cu" signal "BOTTOM")
		(9 "F.Adhes" user "F.Adhesive")
		(11 "B.Adhes" user "B.Adhesive")
		(13 "F.Paste" user "Package Geometry/Pastemask Top")
		(15 "B.Paste" user "Package Geometry/Pastemask Bottom")
		(5 "F.SilkS" user "Ref Des/Silkscreen Top")
		(7 "B.SilkS" user "Ref Des/Silkscreen Bottom")
		(1 "F.Mask" user "Board Geometry/Soldermask Top")
		(3 "B.Mask" user "Board Geometry/Soldermask Bottom")
		(17 "Dwgs.User" user "User.Drawings")
		(19 "Cmts.User" user "User.Comments")
		(21 "Eco1.User" user "User.Eco1")
		(23 "Eco2.User" user "User.Eco2")
		(25 "Edge.Cuts" user "Board Geometry/Outline")
		(27 "Margin" user)
		(31 "F.CrtYd" user "Package Geometry/Place Bound Top")
		(29 "B.CrtYd" user "Package Geometry/Place Bound Bottom")
		(35 "F.Fab" user "Ref Des/Assembly Top")
		(33 "B.Fab" user "Ref Des/Assembly Bottom")
	)
	(footprint ""
		(layer "F.Cu")
		(at 215.9 -209.296 90)
		(property "Reference" "U6"
			(at 0 0 90)
			(layer "F.SilkS")
			(hide yes)
			(effects
				(font
					(size 1.27 1.27)
				)
			)
		)
		(property "Value" "TCA9555PWR-GP"
			(at 0 -6.9342 90)
			(unlocked yes)
			(layer "F.Fab")
			(hide yes)
			(effects
				(font
					(size 1.016 1.016)
					(thickness 0.1524)
				)
			)
		)
		(property "Device Type" "TSOIC24H48"
			(at 0 -8.5852 90)
			(unlocked yes)
			(layer "F.Fab")
			(hide yes)
			(effects
				(font
					(size 1.016 1.016)
					(thickness 0.1524)
				)
			)
		)
		(duplicate_pad_numbers_are_jumpers no)
		(fp_line
			(start 3.81 -1.397)
			(end 3.81 1.397)
			(stroke
				(width 0.1524)
				(type default)
			)
			(layer "F.SilkS")
		)
		(fp_line
			(start -4.2291 -1.397)
			(end 3.81 -1.397)
			(stroke
				(width 0.1524)
				(type default)
			)
			(layer "F.SilkS")
		)
		(fp_line
			(start -4.2291 -0.8001)
			(end -3.429 0)
			(stroke
				(width 0.1524)
				(type default)
			)
			(layer "F.SilkS")
		)
		(fp_line
			(start -3.429 0)
			(end -4.2291 0.8001)
			(stroke
				(width 0.1524)
				(type default)
			)
			(layer "F.SilkS")
		)
		(fp_line
			(start 3.81 1.397)
			(end -4.2291 1.397)
			(stroke
				(width 0.1524)
				(type default)
			)
			(layer "F.SilkS")
		)
		(fp_line
			(start -4.22656 3.81)
			(end -4.2291 1.397)
			(stroke
				(width 0.508)
				(type default)
			)
			(layer "F.SilkS")
		)
		(fp_line
			(start -4.2291 3.937)
			(end -4.2291 -1.397)
			(stroke
				(width 0.1524)
				(type default)
			)
			(layer "F.SilkS")
		)
		(fp_poly
			(pts
				(xy -3.90652 -1.8542) (xy 3.90652 -1.8542) (xy 3.90652 1.8542) (xy -3.90652 1.8542)
			)
			(stroke
				(width 0)
				(type default)
			)
			(fill yes)
			(layer "F.SilkS")
		)
		(fp_poly
			(pts
				(xy -4.2164 3.81) (xy 4.2164 3.81) (xy 4.22656 -3.81) (xy -4.2164 -3.81)
			)
			(stroke
				(width 0)
				(type default)
			)
			(fill no)
			(layer "F.CrtYd")
		)
		(fp_poly
			(pts
				(xy -4.22656 -3.81) (xy 4.22656 -3.81) (xy 4.22656 3.81) (xy -4.22656 3.81)
			)
			(stroke
				(width 0)
				(type default)
			)
			(fill no)
			(layer "F.Fab")
		)
		(pad "1" smd rect
			(at -3.57632 2.8194 90)
			(size 0.3556 1.524)
			(layers "F.Cu" "F.Mask" "F.Paste")
			(net "IO_EXP5_INT_N")
		)
		(pad "2" smd rect
			(at -2.92608 2.8194 90)
			(size 0.3556 1.524)
			(layers "F.Cu" "F.Mask" "F.Paste")
			(net "IO_EXP5_A1")
		)
		(pad "3" smd rect
			(at -2.27584 2.8194 90)
			(size 0.3556 1.524)
			(layers "F.Cu" "F.Mask" "F.Paste")
			(net "IO_EXP5_A2")
		)
		(pad "4" smd rect
			(at -1.6256 2.8194 90)
			(size 0.3556 1.524)
			(layers "F.Cu" "F.Mask" "F.Paste")
			(net "DRIVE_B_16_INS")
		)
		(pad "5" smd rect
			(at -0.97536 2.8194 90)
			(size 0.3556 1.524)
			(layers "F.Cu" "F.Mask" "F.Paste")
			(net "DRIVE_B_17_INS")
		)
		(pad "6" smd rect
			(at -0.32512 2.8194 90)
			(size 0.3556 1.524)
			(layers "F.Cu" "F.Mask" "F.Paste")
			(net "DRIVE_B_18_INS")
		)
		(pad "7" smd rect
			(at 0.32512 2.8194 90)
			(size 0.3556 1.524)
			(layers "F.Cu" "F.Mask" "F.Paste")
			(net "DRIVE_B_19_INS")
		)
		(pad "8" smd rect
			(at 0.97536 2.8194 90)
			(size 0.3556 1.524)
			(layers "F.Cu" "F.Mask" "F.Paste")
			(net "DRIVE_B_20_INS")
		)
		(pad "9" smd rect
			(at 1.6256 2.8194 90)
			(size 0.3556 1.524)
			(layers "F.Cu" "F.Mask" "F.Paste")
			(net "DRIVE_B_21_INS")
		)
		(pad "10" smd rect
			(at 2.27584 2.8194 90)
			(size 0.3556 1.524)
			(layers "F.Cu" "F.Mask" "F.Paste")
			(net "DRIVE_B_22_INS")
		)
		(pad "11" smd rect
			(at 2.92608 2.8194 90)
			(size 0.3556 1.524)
			(layers "F.Cu" "F.Mask" "F.Paste")
			(net "DRIVE_B_23_INS")
		)
		(pad "12" smd rect
			(at 3.57632 2.8194 90)
			(size 0.3556 1.524)
			(layers "F.Cu" "F.Mask" "F.Paste")
			(net "GND")
		)
		(pad "13" smd rect
			(at 3.57632 -2.8194 90)
			(size 0.3556 1.524)
			(layers "F.Cu" "F.Mask" "F.Paste")
			(net "DRIVE_B_24_INS")
		)
		(pad "14" smd rect
			(at 2.92608 -2.8194 90)
			(size 0.3556 1.524)
			(layers "F.Cu" "F.Mask" "F.Paste")
			(net "DRIVE_B_25_INS")
		)
		(pad "15" smd rect
			(at 2.27584 -2.8194 90)
			(size 0.3556 1.524)
			(layers "F.Cu" "F.Mask" "F.Paste")
			(net "DRIVE_B_26_INS")
		)
		(pad "16" smd rect
			(at 1.6256 -2.8194 90)
			(size 0.3556 1.524)
			(layers "F.Cu" "F.Mask" "F.Paste")
			(net "DRIVE_B_27_INS")
		)
		(pad "17" smd rect
			(at 0.97536 -2.8194 90)
			(size 0.3556 1.524)
			(layers "F.Cu" "F.Mask" "F.Paste")
			(net "DRIVE_B_28_INS")
		)
		(pad "18" smd rect
			(at 0.32512 -2.8194 90)
			(size 0.3556 1.524)
			(layers "F.Cu" "F.Mask" "F.Paste")
			(net "DRIVE_B_29_INS")
		)
		(pad "19" smd rect
			(at -0.32512 -2.8194 90)
			(size 0.3556 1.524)
			(layers "F.Cu" "F.Mask" "F.Paste")
			(net "DRIVE_B_30_INS")
		)
		(pad "20" smd rect
			(at -0.97536 -2.8194 90)
			(size 0.3556 1.524)
			(layers "F.Cu" "F.Mask" "F.Paste")
			(net "DRIVE_B_31_INS")
		)
		(pad "21" smd rect
			(at -1.6256 -2.8194 90)
			(size 0.3556 1.524)
			(layers "F.Cu" "F.Mask" "F.Paste")
			(net "IO_EXP5_A0")
		)
		(pad "22" smd rect
			(at -2.27584 -2.8194 90)
			(size 0.3556 1.524)
			(layers "F.Cu" "F.Mask" "F.Paste")
			(net "IO_EXP5_SCL")
		)
		(pad "23" smd rect
			(at -2.92608 -2.8194 90)
			(size 0.3556 1.524)
			(layers "F.Cu" "F.Mask" "F.Paste")
			(net "IO_EXP5_SDA")
		)
		(pad "24" smd rect
			(at -3.57632 -2.8194 90)
			(size 0.3556 1.524)
			(layers "F.Cu" "F.Mask" "F.Paste")
			(net "P3V3_STBY_B")
		)
	)
	(footprint ""
		(layer "F.Cu")
		(at 427.9646 -40.64 -90)
		(property "Reference" "R830"
			(at 0 0 270)
			(layer "F.SilkS")
			(hide yes)
			(effects
				(font
					(size 1.27 1.27)
				)
			)
		)
		(property "Value" "2R6F-GP"
			(at -0.0508 -4.8514 270)
			(unlocked yes)
			(layer "F.Fab")
			(hide yes)
			(effects
				(font
					(size 1.016 1.016)
					(thickness 0.1524)
				)
			)
		)
		(property "Device Type" "R1206H26"
			(at 0 -6.3754 270)
			(unlocked yes)
			(layer "F.Fab")
			(hide yes)
			(effects
				(font
					(size 1.016 1.016)
					(thickness 0.1524)
				)
			)
		)
		(duplicate_pad_numbers_are_jumpers no)
		(fp_line
			(start -1.016 2.2352)
			(end -1.016 -2.2352)
			(stroke
				(width 0.1524)
				(type default)
			)
			(layer "F.SilkS")
		)
		(fp_line
			(start 1.016 2.2352)
			(end -1.016 2.2352)
			(stroke
				(width 0.1524)
				(type default)
			)
			(layer "F.SilkS")
		)
		(fp_line
			(start -1.016 -2.2352)
			(end 1.016 -2.2352)
			(stroke
				(width 0.1524)
				(type default)
			)
			(layer "F.SilkS")
		)
		(fp_line
			(start 1.016 -2.2352)
			(end 1.016 2.2352)
			(stroke
				(width 0.1524)
				(type default)
			)
			(layer "F.SilkS")
		)
		(fp_rect
			(start -1.0922 2.3114)
			(end 1.0922 -2.3114)
			(stroke
				(width 0)
				(type default)
			)
			(fill no)
			(layer "F.CrtYd")
		)
		(fp_poly
			(pts
				(xy -1.0922 -2.3114) (xy 1.0922 -2.3114) (xy 1.0922 2.3114) (xy -1.0922 2.3114)
			)
			(stroke
				(width 0)
				(type default)
			)
			(fill no)
			(layer "F.Fab")
		)
		(pad "1" smd rect
			(at 0 -1.397 270)
			(size 1.651 1.27)
			(layers "F.Cu" "F.Mask" "F.Paste")
			(net "P12V_HDD33")
		)
		(pad "2" smd rect
			(at 0 1.397 270)
			(size 1.651 1.27)
			(layers "F.Cu" "F.Mask" "F.Paste")
			(net "12V_PRE_33")
		)
	)
	(footprint ""
		(layer "F.Cu")
		(at 17.800066 -65.39992)
		(property "Reference" "LED13"
			(at 0 0 0)
			(layer "F.SilkS")
			(hide yes)
			(effects
				(font
					(size 1.27 1.27)
				)
			)
		)
		(property "Value" "LED-BY-19-GP"
			(at -2.132076 1.414018 0)
			(unlocked yes)
			(layer "F.Fab")
			(hide yes)
			(effects
				(font
					(size 1.016 1.016)
					(thickness 0.1524)
				)
			)
		)
		(property "Device Type" "LED-1615-4PH26"
			(at -2.132076 -0.109982 0)
			(unlocked yes)
			(layer "F.Fab")
			(hide yes)
			(effects
				(font
					(size 1.016 1.016)
					(thickness 0.1524)
				)
			)
		)
		(duplicate_pad_numbers_are_jumpers no)
		(fp_line
			(start -1.2954 0.254)
			(end -1.2954 1.6002)
			(stroke
				(width 0.508)
				(type default)
			)
			(layer "F.SilkS")
		)
		(fp_line
			(start -1.2954 1.6002)
			(end 1.2954 1.6002)
			(stroke
				(width 0.508)
				(type default)
			)
			(layer "F.SilkS")
		)
		(fp_line
			(start -1.1176 -1.4224)
			(end 1.1176 -1.4224)
			(stroke
				(width 0.1524)
				(type default)
			)
			(layer "F.SilkS")
		)
		(fp_line
			(start -1.1176 1.4224)
			(end -1.1176 -1.4224)
			(stroke
				(width 0.1524)
				(type default)
			)
			(layer "F.SilkS")
		)
		(fp_line
			(start 1.1176 -1.4224)
			(end 1.1176 1.4224)
			(stroke
				(width 0.1524)
				(type default)
			)
			(layer "F.SilkS")
		)
		(fp_line
			(start 1.1176 1.4224)
			(end -1.1176 1.4224)
			(stroke
				(width 0.1524)
				(type default)
			)
			(layer "F.SilkS")
		)
		(fp_line
			(start 1.2954 1.6002)
			(end 1.2954 0.254)
			(stroke
				(width 0.508)
				(type default)
			)
			(layer "F.SilkS")
		)
		(fp_rect
			(start -0.7493 0.8001)
			(end 0.7493 -0.8001)
			(stroke
				(width 0)
				(type default)
			)
			(fill no)
			(layer "F.CrtYd")
		)
		(fp_poly
			(pts
				(xy -1.3716 1.6764) (xy -1.3716 -1.6764) (xy 1.3716 -1.6764) (xy 1.3716 0.0635) (xy 0.7493 0.0635)
				(xy 0.7493 -0.8001) (xy -0.7493 -0.8001) (xy -0.7493 0.8001) (xy 0.7493 0.8001) (xy 0.7493 0.0762)
				(xy 1.3716 0.0762) (xy 1.3716 1.6764)
			)
			(stroke
				(width 0)
				(type default)
			)
			(fill no)
			(layer "F.CrtYd")
		)
		(fp_rect
			(start -1.3716 1.6764)
			(end 1.3716 -1.6764)
			(stroke
				(width 0)
				(type default)
			)
			(fill no)
			(layer "F.Fab")
		)
		(pad "1" smd rect
			(at 0.50038 -0.73025)
			(size 0.7112 0.8636)
			(layers "F.Cu" "F.Mask" "F.Paste")
			(net "DRV_ACT_12")
		)
		(pad "2" smd rect
			(at -0.50038 -0.73025)
			(size 0.7112 0.8636)
			(layers "F.Cu" "F.Mask" "F.Paste")
			(net "FLT_HDD12")
		)
		(pad "3" smd rect
			(at 0.50038 0.73025)
			(size 0.7112 0.8636)
			(layers "F.Cu" "F.Mask" "F.Paste")
			(net "DRV_ACT_12_N")
		)
		(pad "4" smd rect
			(at -0.50038 0.73025)
			(size 0.7112 0.8636)
			(layers "F.Cu" "F.Mask" "F.Paste")
			(net "FLT_HDD12_N")
		)
	)
	(footprint ""
		(layer "F.Cu")
		(at 445.17056 -360.920284 90)
		(property "Reference" "C535"
			(at 0 0 90)
			(layer "F.SilkS")
			(hide yes)
			(effects
				(font
					(size 1.27 1.27)
				)
			)
		)
		(property "Value" "SC22U25V0MX-2-GP"
			(at -0.00254 -4.78536 90)
			(unlocked yes)
			(layer "F.Fab")
			(hide yes)
			(effects
				(font
					(size 1.016 1.016)
					(thickness 0.1524)
				)
			)
		)
		(property "Device Type" "C1210H111"
			(at -0.00254 -6.38048 90)
			(unlocked yes)
			(layer "F.Fab")
			(hide yes)
			(effects
				(font
					(size 1.016 1.016)
					(thickness 0.1524)
				)
			)
		)
		(duplicate_pad_numbers_are_jumpers no)
		(fp_line
			(start 1.5748 -2.3368)
			(end -1.5748 -2.3368)
			(stroke
				(width 0.1524)
				(type default)
			)
			(layer "F.SilkS")
		)
		(fp_line
			(start -1.5748 -2.3368)
			(end -1.5748 -0.762)
			(stroke
				(width 0.1524)
				(type default)
			)
			(layer "F.SilkS")
		)
		(fp_line
			(start 1.5748 -0.762)
			(end 1.5748 -2.3368)
			(stroke
				(width 0.1524)
				(type default)
			)
			(layer "F.SilkS")
		)
		(fp_line
			(start -1.5748 0.762)
			(end -1.5748 2.3368)
			(stroke
				(width 0.1524)
				(type default)
			)
			(layer "F.SilkS")
		)
		(fp_line
			(start 1.5748 2.3368)
			(end 1.5748 0.762)
			(stroke
				(width 0.1524)
				(type default)
			)
			(layer "F.SilkS")
		)
		(fp_line
			(start -1.5748 2.3368)
			(end 1.5748 2.3368)
			(stroke
				(width 0.1524)
				(type default)
			)
			(layer "F.SilkS")
		)
		(fp_rect
			(start -1.651 2.413)
			(end 1.651 -2.413)
			(stroke
				(width 0)
				(type default)
			)
			(fill no)
			(layer "F.CrtYd")
		)
		(fp_poly
			(pts
				(xy 1.651 2.413) (xy 1.651 -2.413) (xy -1.651 -2.413) (xy -1.651 2.413)
			)
			(stroke
				(width 0)
				(type default)
			)
			(fill no)
			(layer "F.Fab")
		)
		(pad "1" smd rect
			(at 0 -1.4732 90)
			(size 2.794 1.397)
			(layers "F.Cu" "F.Mask" "F.Paste")
			(net "P12V_FAN3")
		)
		(pad "2" smd rect
			(at 0 1.4732 90)
			(size 2.794 1.397)
			(layers "F.Cu" "F.Mask" "F.Paste")
			(net "GND")
		)
	)
	(footprint ""
		(layer "F.Cu")
		(at 476.2246 -5.969)
		(property "Reference" "R892"
			(at 0 0 0)
			(layer "F.SilkS")
			(hide yes)
			(effects
				(font
					(size 1.27 1.27)
				)
			)
		)
		(property "Value" "0R2J-2-GP"
			(at 0.064008 -3.993896 0)
			(unlocked yes)
			(layer "F.Fab")
			(hide yes)
			(effects
				(font
					(size 1.016 1.016)
					(thickness 0.1524)
				)
			)
		)
		(property "Device Type" "R402H16"
			(at 0.064008 -5.517896 0)
			(unlocked yes)
			(layer "F.Fab")
			(hide yes)
			(effects
				(font
					(size 1.016 1.016)
					(thickness 0.1524)
				)
			)
		)
		(duplicate_pad_numbers_are_jumpers no)
		(fp_line
			(start -0.508 -0.9398)
			(end -0.508 0.9398)
			(stroke
				(width 0.1524)
				(type default)
			)
			(layer "F.SilkS")
		)
		(fp_line
			(start 0.508 -0.9398)
			(end -0.508 -0.9398)
			(stroke
				(width 0.1524)
				(type default)
			)
			(layer "F.SilkS")
		)
		(fp_rect
			(start -0.508 0.9398)
			(end 0.508 -0.9398)
			(stroke
				(width 0)
				(type default)
			)
			(fill no)
			(layer "F.CrtYd")
		)
		(fp_rect
			(start -0.508 0.9398)
			(end 0.508 -0.9398)
			(stroke
				(width 0)
				(type default)
			)
			(fill no)
			(layer "F.Fab")
		)
		(pad "1" smd custom
			(at 0 -0.4445)
			(size 0.1397 0.1397)
			(layers "F.Cu" "F.Mask" "F.Paste")
			(net "SW_HDD_G35")
			(options
				(clearance outline)
				(anchor circle)
			)
			(primitives
				(gr_poly
					(pts
						(arc
							(start -0.1778 -0.2794)
							(mid -0.249642 -0.249642)
							(end -0.2794 -0.1778)
						)
						(arc
							(start -0.2794 0.1778)
							(mid -0.249642 0.249642)
							(end -0.1778 0.2794)
						)
						(arc
							(start 0.1778 0.2794)
							(mid 0.249642 0.249642)
							(end 0.2794 0.1778)
						)
						(arc
							(start 0.2794 -0.1778)
							(mid 0.249642 -0.249642)
							(end 0.1778 -0.2794)
						)
					)
					(width 0)
					(fill yes)
				)
			)
		)
		(pad "2" smd custom
			(at 0 0.4445)
			(size 0.1397 0.1397)
			(layers "F.Cu" "F.Mask" "F.Paste")
			(net "SW_HDD_R35")
			(options
				(clearance outline)
				(anchor circle)
			)
			(primitives
				(gr_poly
					(pts
						(arc
							(start -0.1778 -0.2794)
							(mid -0.249642 -0.249642)
							(end -0.2794 -0.1778)
						)
						(arc
							(start -0.2794 0.1778)
							(mid -0.249642 0.249642)
							(end -0.1778 0.2794)
						)
						(arc
							(start 0.1778 0.2794)
							(mid 0.249642 0.249642)
							(end 0.2794 0.1778)
						)
						(arc
							(start 0.2794 -0.1778)
							(mid 0.249642 -0.249642)
							(end 0.1778 -0.2794)
						)
					)
					(width 0)
					(fill yes)
				)
			)
		)
	)
	(footprint ""
		(layer "F.Cu")
		(at 460.314802 -229.49535 -90)
		(property "Reference" "C659"
			(at 0 0 270)
			(layer "F.SilkS")
			(hide yes)
			(effects
				(font
					(size 1.27 1.27)
				)
			)
		)
		(property "Value" "SC1U16V3KX-5GP"
			(at 0 -2.8194 270)
			(unlocked yes)
			(layer "F.Fab")
			(hide yes)
			(effects
				(font
					(size 1.016 1.016)
					(thickness 0.1524)
				)
			)
		)
		(property "Device Type" "C603H36"
			(at 0 -4.3434 270)
			(unlocked yes)
			(layer "F.Fab")
			(hide yes)
			(effects
				(font
					(size 1.016 1.016)
					(thickness 0.1524)
				)
			)
		)
		(duplicate_pad_numbers_are_jumpers no)
		(fp_line
			(start 0.508 0)
			(end -0.508 0)
			(stroke
				(width 0.2032)
				(type default)
			)
			(layer "F.SilkS")
		)
		(fp_rect
			(start -0.5842 1.3335)
			(end 0.5842 -1.3335)
			(stroke
				(width 0)
				(type default)
			)
			(fill no)
			(layer "F.CrtYd")
		)
		(fp_rect
			(start -0.5842 1.3335)
			(end 0.5842 -1.3335)
			(stroke
				(width 0)
				(type default)
			)
			(fill no)
			(layer "F.Fab")
		)
		(pad "1" smd custom
			(at 0 -0.762 270)
			(size 0.2159 0.2159)
			(layers "F.Cu" "F.Mask" "F.Paste")
			(net "P5V_B_3_EN_R")
			(options
				(clearance outline)
				(anchor circle)
			)
			(primitives
				(gr_poly
					(pts
						(arc
							(start -0.3302 -0.4318)
							(mid -0.402042 -0.402042)
							(end -0.4318 -0.3302)
						)
						(arc
							(start -0.4318 0.3302)
							(mid -0.402042 0.402042)
							(end -0.3302 0.4318)
						)
						(arc
							(start 0.3302 0.4318)
							(mid 0.402042 0.402042)
							(end 0.4318 0.3302)
						)
						(arc
							(start 0.4318 -0.3302)
							(mid 0.402042 -0.402042)
							(end 0.3302 -0.4318)
						)
					)
					(width 0)
					(fill yes)
				)
			)
		)
		(pad "2" smd custom
			(at 0 0.762 270)
			(size 0.2159 0.2159)
			(layers "F.Cu" "F.Mask" "F.Paste")
			(net "GND")
			(options
				(clearance outline)
				(anchor circle)
			)
			(primitives
				(gr_poly
					(pts
						(arc
							(start -0.3302 -0.4318)
							(mid -0.402042 -0.402042)
							(end -0.4318 -0.3302)
						)
						(arc
							(start -0.4318 0.3302)
							(mid -0.402042 0.402042)
							(end -0.3302 0.4318)
						)
						(arc
							(start 0.3302 0.4318)
							(mid 0.402042 0.402042)
							(end 0.4318 0.3302)
						)
						(arc
							(start 0.4318 -0.3302)
							(mid 0.402042 -0.402042)
							(end 0.3302 -0.4318)
						)
					)
					(width 0)
					(fill yes)
				)
			)
		)
	)
)
